(kicad_pcb
	(version 20260206)
	(generator "pcbnew")
	(generator_version "10.0")
	(general
		(thickness 1.6)
		(legacy_teardrops no)
	)
	(paper "A4")
	(title_block
		(title "peb — Lightning_PEB_BRD.brd")
		(comment 1 "Lightning (Wiwynn / Facebook NVMe JBOF) / footprints 148-154 of 2563")
	)
	(layers
		(0 "F.Cu" signal "TOP")
		(4 "In1.Cu" signal "L2GND")
		(6 "In2.Cu" signal "L3")
		(8 "In3.Cu" signal "L4VCC")
		(10 "In4.Cu" signal "L5VCC")
		(12 "In5.Cu" signal "L6")
		(14 "In6.Cu" signal "L7GND")
		(2 "B.Cu" signal "BOTTOM")
		(9 "F.Adhes" user "F.Adhesive")
		(11 "B.Adhes" user "B.Adhesive")
		(13 "F.Paste" user "Package Geometry/Pastemask Top")
		(15 "B.Paste" user "Package Geometry/Pastemask Bottom")
		(5 "F.SilkS" user "Ref Des/Silkscreen Top")
		(7 "B.SilkS" user "Ref Des/Silkscreen Bottom")
		(1 "F.Mask" user "Board Geometry/Soldermask Top")
		(3 "B.Mask" user "Board Geometry/Soldermask Bottom")
		(17 "Dwgs.User" user "User.Drawings")
		(19 "Cmts.User" user "User.Comments")
		(21 "Eco1.User" user "User.Eco1")
		(23 "Eco2.User" user "User.Eco2")
		(25 "Edge.Cuts" user "Board Geometry/Outline")
		(27 "Margin" user)
		(31 "F.CrtYd" user "Package Geometry/Place Bound Top")
		(29 "B.CrtYd" user "Package Geometry/Place Bound Bottom")
		(35 "F.Fab" user "Ref Des/Assembly Top")
		(33 "B.Fab" user "Ref Des/Assembly Bottom")
	)
	(footprint ""
		(layer "F.Cu")
		(at 131.040124 -196.443092)
		(property "Reference" "R7944"
			(at 0 0 0)
			(layer "F.SilkS")
			(hide yes)
			(effects
				(font
					(size 1.27 1.27)
				)
			)
		)
		(property "Value" "0R2J-2-GP"
			(at 0.064008 -3.993896 0)
			(unlocked yes)
			(layer "F.Fab")
			(hide yes)
			(effects
				(font
					(size 1.016 1.016)
					(thickness 0.1524)
				)
			)
		)
		(property "Device Type" "R402H16"
			(at 0.064008 -5.517896 0)
			(unlocked yes)
			(layer "F.Fab")
			(hide yes)
			(effects
				(font
					(size 1.016 1.016)
					(thickness 0.1524)
				)
			)
		)
		(duplicate_pad_numbers_are_jumpers no)
		(fp_line
			(start -0.508 -0.9398)
			(end -0.508 0.9398)
			(stroke
				(width 0.1524)
				(type default)
			)
			(layer "F.SilkS")
		)
		(fp_line
			(start 0.508 -0.9398)
			(end -0.508 -0.9398)
			(stroke
				(width 0.1524)
				(type default)
			)
			(layer "F.SilkS")
		)
		(fp_rect
			(start -0.508 0.9398)
			(end 0.508 -0.9398)
			(stroke
				(width 0)
				(type default)
			)
			(fill no)
			(layer "F.CrtYd")
		)
		(fp_rect
			(start -0.508 0.9398)
			(end 0.508 -0.9398)
			(stroke
				(width 0)
				(type default)
			)
			(fill no)
			(layer "F.Fab")
		)
		(pad "1" smd custom
			(at 0 -0.4445)
			(size 0.1397 0.1397)
			(layers "F.Cu" "F.Mask" "F.Paste")
			(net "SSD_ATNLED#2")
			(options
				(clearance outline)
				(anchor circle)
			)
			(primitives
				(gr_poly
					(pts
						(arc
							(start -0.1778 -0.2794)
							(mid -0.249642 -0.249642)
							(end -0.2794 -0.1778)
						)
						(arc
							(start -0.2794 0.1778)
							(mid -0.249642 0.249642)
							(end -0.1778 0.2794)
						)
						(arc
							(start 0.1778 0.2794)
							(mid 0.249642 0.249642)
							(end 0.2794 0.1778)
						)
						(arc
							(start 0.2794 -0.1778)
							(mid 0.249642 -0.249642)
							(end 0.1778 -0.2794)
						)
					)
					(width 0)
					(fill yes)
				)
			)
		)
		(pad "2" smd custom
			(at 0 0.4445)
			(size 0.1397 0.1397)
			(layers "F.Cu" "F.Mask" "F.Paste")
			(net "SSD_ATNLED#2_R")
			(options
				(clearance outline)
				(anchor circle)
			)
			(primitives
				(gr_poly
					(pts
						(arc
							(start -0.1778 -0.2794)
							(mid -0.249642 -0.249642)
							(end -0.2794 -0.1778)
						)
						(arc
							(start -0.2794 0.1778)
							(mid -0.249642 0.249642)
							(end -0.1778 0.2794)
						)
						(arc
							(start 0.1778 0.2794)
							(mid 0.249642 0.249642)
							(end 0.2794 0.1778)
						)
						(arc
							(start 0.2794 -0.1778)
							(mid 0.249642 -0.249642)
							(end 0.1778 -0.2794)
						)
					)
					(width 0)
					(fill yes)
				)
			)
		)
	)
	(footprint ""
		(layer "F.Cu")
		(at 192.9384 -21.971 -90)
		(property "Reference" "R696"
			(at 0 0 270)
			(layer "F.SilkS")
			(hide yes)
			(effects
				(font
					(size 1.27 1.27)
				)
			)
		)
		(property "Value" "4K7R2F-GP"
			(at 0.064008 -3.993896 270)
			(unlocked yes)
			(layer "F.Fab")
			(hide yes)
			(effects
				(font
					(size 1.016 1.016)
					(thickness 0.1524)
				)
			)
		)
		(property "Device Type" "R402H16"
			(at 0.064008 -5.517896 270)
			(unlocked yes)
			(layer "F.Fab")
			(hide yes)
			(effects
				(font
					(size 1.016 1.016)
					(thickness 0.1524)
				)
			)
		)
		(duplicate_pad_numbers_are_jumpers no)
		(fp_line
			(start -0.508 -0.9398)
			(end -0.508 0.9398)
			(stroke
				(width 0.1524)
				(type default)
			)
			(layer "F.SilkS")
		)
		(fp_line
			(start 0.508 -0.9398)
			(end -0.508 -0.9398)
			(stroke
				(width 0.1524)
				(type default)
			)
			(layer "F.SilkS")
		)
		(fp_rect
			(start -0.508 0.9398)
			(end 0.508 -0.9398)
			(stroke
				(width 0)
				(type default)
			)
			(fill no)
			(layer "F.CrtYd")
		)
		(fp_rect
			(start -0.508 0.9398)
			(end 0.508 -0.9398)
			(stroke
				(width 0)
				(type default)
			)
			(fill no)
			(layer "F.Fab")
		)
		(pad "1" smd custom
			(at 0 -0.4445 270)
			(size 0.1397 0.1397)
			(layers "F.Cu" "F.Mask" "F.Paste")
			(net "MINISAS_CN15_A_I2C_INT#")
			(options
				(clearance outline)
				(anchor circle)
			)
			(primitives
				(gr_poly
					(pts
						(arc
							(start -0.1778 -0.2794)
							(mid -0.249642 -0.249642)
							(end -0.2794 -0.1778)
						)
						(arc
							(start -0.2794 0.1778)
							(mid -0.249642 0.249642)
							(end -0.1778 0.2794)
						)
						(arc
							(start 0.1778 0.2794)
							(mid 0.249642 0.249642)
							(end 0.2794 0.1778)
						)
						(arc
							(start 0.2794 -0.1778)
							(mid 0.249642 -0.249642)
							(end 0.1778 -0.2794)
						)
					)
					(width 0)
					(fill yes)
				)
			)
		)
		(pad "2" smd custom
			(at 0 0.4445 270)
			(size 0.1397 0.1397)
			(layers "F.Cu" "F.Mask" "F.Paste")
			(net "P3V3_STBY")
			(options
				(clearance outline)
				(anchor circle)
			)
			(primitives
				(gr_poly
					(pts
						(arc
							(start -0.1778 -0.2794)
							(mid -0.249642 -0.249642)
							(end -0.2794 -0.1778)
						)
						(arc
							(start -0.2794 0.1778)
							(mid -0.249642 0.249642)
							(end -0.1778 0.2794)
						)
						(arc
							(start 0.1778 0.2794)
							(mid 0.249642 0.249642)
							(end 0.2794 0.1778)
						)
						(arc
							(start 0.2794 -0.1778)
							(mid 0.249642 -0.249642)
							(end 0.1778 -0.2794)
						)
					)
					(width 0)
					(fill yes)
				)
			)
		)
	)
	(footprint ""
		(layer "F.Cu")
		(at 121.059956 -41.273222 90)
		(property "Reference" "Q4"
			(at 0 0 90)
			(layer "F.SilkS")
			(hide yes)
			(effects
				(font
					(size 1.27 1.27)
				)
			)
		)
		(property "Value" "PN2907AL-T92-K-GP"
			(at 0.6223 -2.5146 90)
			(unlocked yes)
			(layer "F.Fab")
			(hide yes)
			(effects
				(font
					(size 1.016 1.016)
					(thickness 0.1524)
				)
			)
		)
		(property "Device Type" "TO-92-CBE-4635H591"
			(at 0.6223 -4.0386 90)
			(unlocked yes)
			(layer "F.Fab")
			(hide yes)
			(effects
				(font
					(size 1.016 1.016)
					(thickness 0.1524)
				)
			)
		)
		(duplicate_pad_numbers_are_jumpers no)
		(fp_line
			(start 2.54 -1.2827)
			(end 2.54 0.1905)
			(stroke
				(width 0.1524)
				(type default)
			)
			(layer "F.SilkS")
		)
		(fp_line
			(start -2.54 -1.2827)
			(end 2.54 -1.2827)
			(stroke
				(width 0.1524)
				(type default)
			)
			(layer "F.SilkS")
		)
		(fp_line
			(start -2.54 0.1905)
			(end -2.54 -1.2827)
			(stroke
				(width 0.1524)
				(type default)
			)
			(layer "F.SilkS")
		)
		(fp_arc
			(start 2.54 0.1905)
			(mid 0 2.7305)
			(end -2.54 0.1905)
			(stroke
				(width 0.1524)
				(type default)
			)
			(layer "F.SilkS")
		)
		(fp_poly
			(pts
				(arc
					(start 2.286 0.1905)
					(mid 0 2.4765)
					(end -2.286 0.1905)
				)
				(xy -2.286 -1.0287) (xy 2.286 -1.0287)
			)
			(stroke
				(width 0)
				(type default)
			)
			(fill no)
			(layer "F.CrtYd")
		)
		(fp_poly
			(pts
				(arc
					(start 2.794 0.1905)
					(mid 0 2.9845)
					(end -2.794 0.1905)
				)
				(xy -2.794 -1.5367) (xy 2.794 -1.5367) (xy 2.794 -0.00635) (xy 2.286 -0.00635) (xy 2.286 -1.0287)
				(xy -2.286 -1.0287)
				(arc
					(start -2.286 0.1905)
					(mid 0 2.4765)
					(end 2.286 0.1905)
				)
				(xy 2.286 0.00635) (xy 2.794 0.00635)
			)
			(stroke
				(width 0)
				(type default)
			)
			(fill no)
			(layer "F.CrtYd")
		)
		(fp_poly
			(pts
				(arc
					(start 2.794 0.1905)
					(mid 0 2.9845)
					(end -2.794 0.1905)
				)
				(xy -2.794 -1.5367) (xy 2.794 -1.5367)
			)
			(stroke
				(width 0)
				(type default)
			)
			(fill no)
			(layer "F.Fab")
		)
		(pad "B" thru_hole oval
			(at 0 0 90)
			(size 1.0414 1.1684)
			(drill 0.762)
			(layers "*.Cu" "*.Mask")
			(remove_unused_layers no)
			(net "TEMP_SENSOR_DXN_BJT")
			(clearance 0.2159)
			(thermal_gap 0.2159)
		)
		(pad "C" thru_hole oval
			(at -1.27 0 90)
			(size 1.0414 1.1684)
			(drill 0.762)
			(layers "*.Cu" "*.Mask")
			(remove_unused_layers no)
			(net "TEMP_SENSOR_C")
			(clearance 0.2159)
			(thermal_gap 0.2159)
		)
		(pad "E" thru_hole oval
			(at 1.27 0 90)
			(size 1.0414 1.1684)
			(drill 0.762)
			(layers "*.Cu" "*.Mask")
			(remove_unused_layers no)
			(net "TEMP_SENSOR_DXP_R")
			(clearance 0.2159)
			(thermal_gap 0.2159)
		)
	)
	(footprint ""
		(layer "F.Cu")
		(at 56.990488 -143.254476 90)
		(property "Reference" "R415"
			(at 0 0 90)
			(layer "F.SilkS")
			(hide yes)
			(effects
				(font
					(size 1.27 1.27)
				)
			)
		)
		(property "Value" "0R2J-2-GP"
			(at 0.064008 -3.993896 90)
			(unlocked yes)
			(layer "F.Fab")
			(hide yes)
			(effects
				(font
					(size 1.016 1.016)
					(thickness 0.1524)
				)
			)
		)
		(property "Device Type" "R402H16"
			(at 0.064008 -5.517896 90)
			(unlocked yes)
			(layer "F.Fab")
			(hide yes)
			(effects
				(font
					(size 1.016 1.016)
					(thickness 0.1524)
				)
			)
		)
		(duplicate_pad_numbers_are_jumpers no)
		(fp_line
			(start 0.508 -0.9398)
			(end -0.508 -0.9398)
			(stroke
				(width 0.1524)
				(type default)
			)
			(layer "F.SilkS")
		)
		(fp_line
			(start -0.508 -0.9398)
			(end -0.508 0.9398)
			(stroke
				(width 0.1524)
				(type default)
			)
			(layer "F.SilkS")
		)
		(fp_rect
			(start -0.508 0.9398)
			(end 0.508 -0.9398)
			(stroke
				(width 0)
				(type default)
			)
			(fill no)
			(layer "F.CrtYd")
		)
		(fp_rect
			(start -0.508 0.9398)
			(end 0.508 -0.9398)
			(stroke
				(width 0)
				(type default)
			)
			(fill no)
			(layer "F.Fab")
		)
		(pad "1" smd custom
			(at 0 -0.4445 90)
			(size 0.1397 0.1397)
			(layers "F.Cu" "F.Mask" "F.Paste")
			(net "GPIOM0_I210_PERST_N")
			(options
				(clearance outline)
				(anchor circle)
			)
			(primitives
				(gr_poly
					(pts
						(arc
							(start -0.1778 -0.2794)
							(mid -0.249642 -0.249642)
							(end -0.2794 -0.1778)
						)
						(arc
							(start -0.2794 0.1778)
							(mid -0.249642 0.249642)
							(end -0.1778 0.2794)
						)
						(arc
							(start 0.1778 0.2794)
							(mid 0.249642 0.249642)
							(end 0.2794 0.1778)
						)
						(arc
							(start 0.2794 -0.1778)
							(mid 0.249642 -0.249642)
							(end 0.1778 -0.2794)
						)
					)
					(width 0)
					(fill yes)
				)
			)
		)
		(pad "2" smd custom
			(at 0 0.4445 90)
			(size 0.1397 0.1397)
			(layers "F.Cu" "F.Mask" "F.Paste")
			(net "BMC_I210_PERST_N")
			(options
				(clearance outline)
				(anchor circle)
			)
			(primitives
				(gr_poly
					(pts
						(arc
							(start -0.1778 -0.2794)
							(mid -0.249642 -0.249642)
							(end -0.2794 -0.1778)
						)
						(arc
							(start -0.2794 0.1778)
							(mid -0.249642 0.249642)
							(end -0.1778 0.2794)
						)
						(arc
							(start 0.1778 0.2794)
							(mid 0.249642 0.249642)
							(end 0.2794 0.1778)
						)
						(arc
							(start 0.2794 -0.1778)
							(mid 0.249642 -0.249642)
							(end 0.1778 -0.2794)
						)
					)
					(width 0)
					(fill yes)
				)
			)
		)
	)
	(footprint ""
		(layer "F.Cu")
		(at 135.3693 -33.54324)
		(property "Reference" "C381"
			(at 0 0 0)
			(layer "F.SilkS")
			(hide yes)
			(effects
				(font
					(size 1.27 1.27)
				)
			)
		)
		(property "Value" "SCD22U10V2KX-1GP"
			(at 1.1811 -2.7051 0)
			(unlocked yes)
			(layer "F.Fab")
			(hide yes)
			(effects
				(font
					(size 1.016 1.016)
					(thickness 0.1524)
				)
			)
		)
		(property "Device Type" "C402H22"
			(at 1.1811 -4.2291 0)
			(unlocked yes)
			(layer "F.Fab")
			(hide yes)
			(effects
				(font
					(size 1.016 1.016)
					(thickness 0.1524)
				)
			)
		)
		(duplicate_pad_numbers_are_jumpers no)
		(fp_rect
			(start -0.4318 0.9525)
			(end 0.4318 -0.9525)
			(stroke
				(width 0)
				(type default)
			)
			(fill no)
			(layer "F.CrtYd")
		)
		(fp_rect
			(start -0.4318 0.9525)
			(end 0.4318 -0.9525)
			(stroke
				(width 0)
				(type default)
			)
			(fill no)
			(layer "F.Fab")
		)
		(pad "1" smd custom
			(at 0 -0.4445)
			(size 0.1524 0.1524)
			(layers "F.Cu" "F.Mask" "F.Paste")
			(net "PCIE_TX_CAP_P80")
			(options
				(clearance outline)
				(anchor circle)
			)
			(primitives
				(gr_poly
					(pts
						(arc
							(start 0.3048 -0.2032)
							(mid 0.275042 -0.275042)
							(end 0.2032 -0.3048)
						)
						(arc
							(start -0.2032 -0.3048)
							(mid -0.275042 -0.275042)
							(end -0.3048 -0.2032)
						)
						(arc
							(start -0.3048 0.2032)
							(mid -0.275042 0.275042)
							(end -0.2032 0.3048)
						)
						(arc
							(start 0.2032 0.3048)
							(mid 0.275042 0.275042)
							(end 0.3048 0.2032)
						)
					)
					(width 0)
					(fill yes)
				)
			)
		)
		(pad "2" smd custom
			(at 0 0.4445)
			(size 0.1524 0.1524)
			(layers "F.Cu" "F.Mask" "F.Paste")
			(net "PCIE_TX_P80")
			(options
				(clearance outline)
				(anchor circle)
			)
			(primitives
				(gr_poly
					(pts
						(arc
							(start 0.3048 -0.2032)
							(mid 0.275042 -0.275042)
							(end 0.2032 -0.3048)
						)
						(arc
							(start -0.2032 -0.3048)
							(mid -0.275042 -0.275042)
							(end -0.3048 -0.2032)
						)
						(arc
							(start -0.3048 0.2032)
							(mid -0.275042 0.275042)
							(end -0.2032 0.3048)
						)
						(arc
							(start 0.2032 0.3048)
							(mid 0.275042 0.275042)
							(end 0.3048 0.2032)
						)
					)
					(width 0)
					(fill yes)
				)
			)
		)
	)
	(footprint ""
		(layer "F.Cu")
		(at 225.8314 -15.4686 90)
		(property "Reference" "U82"
			(at 0 0 90)
			(layer "F.SilkS")
			(hide yes)
			(effects
				(font
					(size 1.27 1.27)
				)
			)
		)
		(property "Value" "ADM6315-26D3ARTZR7-4-GP"
			(at -0.0127 -12.8016 90)
			(unlocked yes)
			(layer "F.Fab")
			(hide yes)
			(effects
				(font
					(size 1.016 1.016)
					(thickness 0.1524)
				)
			)
		)
		(property "Device Type" "SOT-143-6H49"
			(at -0.0635 -14.6812 90)
			(unlocked yes)
			(layer "F.Fab")
			(hide yes)
			(effects
				(font
					(size 1.016 1.016)
					(thickness 0.1524)
				)
			)
		)
		(duplicate_pad_numbers_are_jumpers no)
		(fp_line
			(start 1.6891 -1.778)
			(end 1.6891 1.778)
			(stroke
				(width 0.1524)
				(type default)
			)
			(layer "F.SilkS")
		)
		(fp_line
			(start -1.6891 -1.778)
			(end 1.6891 -1.778)
			(stroke
				(width 0.1524)
				(type default)
			)
			(layer "F.SilkS")
		)
		(fp_line
			(start 1.6891 1.778)
			(end -1.6891 1.778)
			(stroke
				(width 0.1524)
				(type default)
			)
			(layer "F.SilkS")
		)
		(fp_line
			(start -1.6891 1.778)
			(end -1.6891 -1.778)
			(stroke
				(width 0.1524)
				(type default)
			)
			(layer "F.SilkS")
		)
		(fp_line
			(start -0.3175 1.8669)
			(end -1.7907 1.8669)
			(stroke
				(width 0.3302)
				(type default)
			)
			(layer "F.SilkS")
		)
		(fp_line
			(start -1.7907 1.8669)
			(end -1.7907 0.3937)
			(stroke
				(width 0.3302)
				(type default)
			)
			(layer "F.SilkS")
		)
		(fp_poly
			(pts
				(xy -0.7239 1.8542) (xy -1.3335 2.4638) (xy -0.1143 2.4638)
			)
			(stroke
				(width 0)
				(type default)
			)
			(fill yes)
			(layer "F.SilkS")
		)
		(fp_rect
			(start -1.9431 2.032)
			(end 1.9431 -2.032)
			(stroke
				(width 0)
				(type default)
			)
			(fill no)
			(layer "F.CrtYd")
		)
		(fp_poly
			(pts
				(xy 1.9431 2.032) (xy 1.9431 -2.032) (xy -1.9431 -2.032) (xy -1.9431 2.032)
			)
			(stroke
				(width 0)
				(type default)
			)
			(fill no)
			(layer "F.Fab")
		)
		(pad "1" smd rect
			(at -0.75311 0.9652 90)
			(size 1.1176 1.1176)
			(layers "F.Cu" "F.Mask" "F.Paste")
			(net "GND")
		)
		(pad "2" smd rect
			(at 0.9525 0.9652 90)
			(size 0.7112 1.1176)
			(layers "F.Cu" "F.Mask" "F.Paste")
			(net "U82_RST#")
		)
		(pad "3" smd rect
			(at 0.9525 -0.9652 90)
			(size 0.7112 1.1176)
			(layers "F.Cu" "F.Mask" "F.Paste")
			(net "U82_MR#")
		)
		(pad "4" smd rect
			(at -0.9525 -0.9652 90)
			(size 0.7112 1.1176)
			(layers "F.Cu" "F.Mask" "F.Paste")
			(net "P3V3_STBY")
		)
	)
	(footprint ""
		(layer "F.Cu")
		(at 97.992184 -212.420454 180)
		(property "Reference" "C156"
			(at 0 0 180)
			(layer "F.SilkS")
			(hide yes)
			(effects
				(font
					(size 1.27 1.27)
				)
			)
		)
		(property "Value" "SCD22U10V2KX-1GP"
			(at 1.1811 -2.7051 180)
			(unlocked yes)
			(layer "F.Fab")
			(hide yes)
			(effects
				(font
					(size 1.016 1.016)
					(thickness 0.1524)
				)
			)
		)
		(property "Device Type" "C402H22"
			(at 1.1811 -4.2291 180)
			(unlocked yes)
			(layer "F.Fab")
			(hide yes)
			(effects
				(font
					(size 1.016 1.016)
					(thickness 0.1524)
				)
			)
		)
		(duplicate_pad_numbers_are_jumpers no)
		(fp_rect
			(start -0.4318 0.9525)
			(end 0.4318 -0.9525)
			(stroke
				(width 0)
				(type default)
			)
			(fill no)
			(layer "F.CrtYd")
		)
		(fp_rect
			(start -0.4318 0.9525)
			(end 0.4318 -0.9525)
			(stroke
				(width 0)
				(type default)
			)
			(fill no)
			(layer "F.Fab")
		)
		(pad "1" smd custom
			(at 0 -0.4445 180)
			(size 0.1524 0.1524)
			(layers "F.Cu" "F.Mask" "F.Paste")
			(net "PCIE_TX_CAP_P63")
			(options
				(clearance outline)
				(anchor circle)
			)
			(primitives
				(gr_poly
					(pts
						(arc
							(start 0.3048 -0.2032)
							(mid 0.275042 -0.275042)
							(end 0.2032 -0.3048)
						)
						(arc
							(start -0.2032 -0.3048)
							(mid -0.275042 -0.275042)
							(end -0.3048 -0.2032)
						)
						(arc
							(start -0.3048 0.2032)
							(mid -0.275042 0.275042)
							(end -0.2032 0.3048)
						)
						(arc
							(start 0.2032 0.3048)
							(mid 0.275042 0.275042)
							(end 0.3048 0.2032)
						)
					)
					(width 0)
					(fill yes)
				)
			)
		)
		(pad "2" smd custom
			(at 0 0.4445 180)
			(size 0.1524 0.1524)
			(layers "F.Cu" "F.Mask" "F.Paste")
			(net "PCIE_TX_P63")
			(options
				(clearance outline)
				(anchor circle)
			)
			(primitives
				(gr_poly
					(pts
						(arc
							(start 0.3048 -0.2032)
							(mid 0.275042 -0.275042)
							(end 0.2032 -0.3048)
						)
						(arc
							(start -0.2032 -0.3048)
							(mid -0.275042 -0.275042)
							(end -0.3048 -0.2032)
						)
						(arc
							(start -0.3048 0.2032)
							(mid -0.275042 0.275042)
							(end -0.2032 0.3048)
						)
						(arc
							(start 0.2032 0.3048)
							(mid 0.275042 0.275042)
							(end 0.3048 0.2032)
						)
					)
					(width 0)
					(fill yes)
				)
			)
		)
	)
)
